(kicad_pcb
	(version 20260206)
	(generator "pcbnew")
	(generator_version "10.0")
	(general
		(thickness 1.6)
		(legacy_teardrops no)
	)
	(paper "A4")
	(title_block
		(title "panther-plus-userver — 13130-1b_20150205.brd")
		(comment 1 "Honey Badger (Wiwynn) / footprint 1214 of 1509 (DIMM3), pads 37-43 of 210")
	)
	(layers
		(0 "F.Cu" signal "TOP")
		(4 "In1.Cu" signal "L2")
		(6 "In2.Cu" signal "L3")
		(8 "In3.Cu" signal "L4")
		(10 "In4.Cu" signal "L5")
		(12 "In5.Cu" signal "L6")
		(14 "In6.Cu" signal "L7")
		(16 "In7.Cu" signal "L8")
		(18 "In8.Cu" signal "L9")
		(20 "In9.Cu" signal "L10")
		(22 "In10.Cu" signal "L11")
		(2 "B.Cu" signal "BOTTOM")
		(9 "F.Adhes" user "F.Adhesive")
		(11 "B.Adhes" user "B.Adhesive")
		(13 "F.Paste" user "Package Geometry/Pastemask Top")
		(15 "B.Paste" user "Package Geometry/Pastemask Bottom")
		(5 "F.SilkS" user "Ref Des/Silkscreen Top")
		(7 "B.SilkS" user "Ref Des/Silkscreen Bottom")
		(1 "F.Mask" user "Board Geometry/Soldermask Top")
		(3 "B.Mask" user "Board Geometry/Soldermask Bottom")
		(17 "Dwgs.User" user "User.Drawings")
		(19 "Cmts.User" user "User.Comments")
		(21 "Eco1.User" user "User.Eco1")
		(23 "Eco2.User" user "User.Eco2")
		(25 "Edge.Cuts" user "Board Geometry/Outline")
		(27 "Margin" user)
		(31 "F.CrtYd" user "Package Geometry/Place Bound Top")
		(29 "B.CrtYd" user "Package Geometry/Place Bound Bottom")
		(35 "F.Fab" user "Ref Des/Assembly Top")
		(33 "B.Fab" user "Ref Des/Assembly Bottom")
	)
	(footprint ""
		(layer "B.Cu")
		(at 159.999934 -5.790692)
		(property "Reference" "DIMM3"
			(at 0 0 0)
			(layer "B.SilkS")
			(hide yes)
			(effects
				(font
					(size 1.27 1.27)
				)
				(justify mirror)
			)
		)
		(property "Value" "DDR3-204P-142-COLAY-1-GP-U"
			(at 41.312338 -16.676878 0)
			(unlocked yes)
			(layer "B.Fab")
			(hide yes)
			(effects
				(font
					(size 1.016 1.016)
					(thickness 0.1524)
				)
				(justify mirror)
			)
		)
		(property "Device Type" "AS0A626-J8R6-7H-COLAY-1"
			(at 41.312338 -18.200878 0)
			(unlocked yes)
			(layer "B.Fab")
			(hide yes)
			(effects
				(font
					(size 1.016 1.016)
					(thickness 0.1524)
				)
				(justify mirror)
			)
		)
		(duplicate_pad_numbers_are_jumpers no)
		(pad "35" smd custom
			(at -21.450046 -4.100068 180)
			(size 0.1143 0.1143)
			(layers "B.Cu" "B.Mask" "B.Paste")
			(net "GND")
			(options
				(clearance outline)
				(anchor circle)
			)
			(primitives
				(gr_poly
					(pts
						(xy 0 -0.9017) (xy -0.03175 -0.89916) (xy -0.0635 -0.889) (xy -0.09144 -0.87376) (xy -0.11684 -0.85344)
						(xy -0.13716 -0.82804) (xy -0.1524 -0.8001) (xy -0.16256 -0.76835) (xy -0.1651 -0.7366) (xy -0.1651 -0.19685)
						(xy -0.17272 -0.18923) (xy -0.17907 -0.18034) (xy -0.18669 -0.17145) (xy -0.19177 -0.16256) (xy -0.19812 -0.15367)
						(xy -0.20828 -0.13335) (xy -0.21971 -0.10287) (xy -0.22225 -0.09271) (xy -0.22479 -0.08128) (xy -0.22606 -0.07112)
						(xy -0.2286 -0.05969) (xy -0.2286 -0.01651) (xy -0.22606 -0.00508) (xy -0.22479 0.00508) (xy -0.22225 0.01651)
						(xy -0.21971 0.02667) (xy -0.20828 0.05715) (xy -0.19812 0.07747) (xy -0.19177 0.08636) (xy -0.18669 0.09525)
						(xy -0.17907 0.10414) (xy -0.17272 0.11303) (xy -0.1651 0.12065) (xy -0.1651 0.7366) (xy -0.16256 0.76835)
						(xy -0.1524 0.8001) (xy -0.13716 0.82804) (xy -0.11684 0.85344) (xy -0.09144 0.87376) (xy -0.0635 0.889)
						(xy -0.03175 0.89916) (xy 0 0.9017) (xy 0.03175 0.89916) (xy 0.0635 0.889) (xy 0.09144 0.87376)
						(xy 0.11684 0.85344) (xy 0.13716 0.82804) (xy 0.1524 0.8001) (xy 0.16256 0.76835) (xy 0.1651 0.7366)
						(xy 0.1651 0.11938) (xy 0.17272 0.11176) (xy 0.19812 0.0762) (xy 0.2032 0.06604) (xy 0.20701 0.05715)
						(xy 0.21209 0.04699) (xy 0.2159 0.03683) (xy 0.21844 0.02667) (xy 0.22225 0.01524) (xy 0.22352 0.00508)
						(xy 0.22606 -0.00508) (xy 0.22733 -0.01651) (xy 0.22733 -0.02667) (xy 0.2286 -0.0381) (xy 0.22733 -0.04953)
						(xy 0.22733 -0.05969) (xy 0.22606 -0.07112) (xy 0.22352 -0.08128) (xy 0.22225 -0.09144) (xy 0.21844 -0.10287)
						(xy 0.2159 -0.11303) (xy 0.21209 -0.12319) (xy 0.20701 -0.13335) (xy 0.2032 -0.14224) (xy 0.19812 -0.1524)
						(xy 0.17272 -0.18796) (xy 0.1651 -0.19558) (xy 0.1651 -0.7366) (xy 0.16256 -0.76835) (xy 0.1524 -0.8001)
						(xy 0.13716 -0.82804) (xy 0.11684 -0.85344) (xy 0.09144 -0.87376) (xy 0.0635 -0.889) (xy 0.03175 -0.89916)
					)
					(width 0)
					(fill yes)
				)
			)
		)
		(pad "36" smd custom
			(at -21.150072 4.100068 180)
			(size 0.1143 0.1143)
			(layers "B.Cu" "B.Mask" "B.Paste")
			(net "M_B_DQ15")
			(options
				(clearance outline)
				(anchor circle)
			)
			(primitives
				(gr_poly
					(pts
						(xy 0 -0.9017) (xy -0.03175 -0.89916) (xy -0.0635 -0.889) (xy -0.09144 -0.87376) (xy -0.11684 -0.85344)
						(xy -0.13716 -0.82804) (xy -0.1524 -0.8001) (xy -0.16256 -0.76835) (xy -0.1651 -0.7366) (xy -0.1651 -0.11938)
						(xy -0.17272 -0.11176) (xy -0.19812 -0.0762) (xy -0.2032 -0.06604) (xy -0.20701 -0.05715) (xy -0.21209 -0.04699)
						(xy -0.2159 -0.03683) (xy -0.21844 -0.02667) (xy -0.22225 -0.01524) (xy -0.22352 -0.00508) (xy -0.22606 0.00508)
						(xy -0.22733 0.01651) (xy -0.22733 0.02667) (xy -0.2286 0.0381) (xy -0.22733 0.04953) (xy -0.22733 0.05969)
						(xy -0.22606 0.07112) (xy -0.22352 0.08128) (xy -0.22225 0.09144) (xy -0.21844 0.10287) (xy -0.2159 0.11303)
						(xy -0.21209 0.12319) (xy -0.20701 0.13335) (xy -0.2032 0.14224) (xy -0.19812 0.1524) (xy -0.17272 0.18796)
						(xy -0.1651 0.19558) (xy -0.1651 0.7366) (xy -0.16256 0.76835) (xy -0.1524 0.8001) (xy -0.13716 0.82804)
						(xy -0.11684 0.85344) (xy -0.09144 0.87376) (xy -0.0635 0.889) (xy -0.03175 0.89916) (xy 0 0.9017)
						(xy 0.03175 0.89916) (xy 0.0635 0.889) (xy 0.09144 0.87376) (xy 0.11684 0.85344) (xy 0.13716 0.82804)
						(xy 0.1524 0.8001) (xy 0.16256 0.76835) (xy 0.1651 0.7366) (xy 0.1651 0.19685) (xy 0.17272 0.18923)
						(xy 0.17907 0.18034) (xy 0.18669 0.17145) (xy 0.19177 0.16256) (xy 0.19812 0.15367) (xy 0.20828 0.13335)
						(xy 0.21971 0.10287) (xy 0.22225 0.09271) (xy 0.22479 0.08128) (xy 0.22606 0.07112) (xy 0.2286 0.05969)
						(xy 0.2286 0.01651) (xy 0.22606 0.00508) (xy 0.22479 -0.00508) (xy 0.22225 -0.01651) (xy 0.21971 -0.02667)
						(xy 0.20828 -0.05715) (xy 0.19812 -0.07747) (xy 0.19177 -0.08636) (xy 0.18669 -0.09525) (xy 0.17907 -0.10414)
						(xy 0.17272 -0.11303) (xy 0.1651 -0.12065) (xy 0.1651 -0.7366) (xy 0.16256 -0.76835) (xy 0.1524 -0.8001)
						(xy 0.13716 -0.82804) (xy 0.11684 -0.85344) (xy 0.09144 -0.87376) (xy 0.0635 -0.889) (xy 0.03175 -0.89916)
					)
					(width 0)
					(fill yes)
				)
			)
		)
		(pad "37" smd custom
			(at -20.850098 -4.100068 180)
			(size 0.1143 0.1143)
			(layers "B.Cu" "B.Mask" "B.Paste")
			(net "M_B_DQ16")
			(options
				(clearance outline)
				(anchor circle)
			)
			(primitives
				(gr_poly
					(pts
						(xy 0 -0.9017) (xy -0.03175 -0.89916) (xy -0.0635 -0.889) (xy -0.09144 -0.87376) (xy -0.11684 -0.85344)
						(xy -0.13716 -0.82804) (xy -0.1524 -0.8001) (xy -0.16256 -0.76835) (xy -0.1651 -0.7366) (xy -0.1651 -0.44958)
						(xy -0.17272 -0.44196) (xy -0.19812 -0.4064) (xy -0.2032 -0.39624) (xy -0.20701 -0.38735) (xy -0.21209 -0.37719)
						(xy -0.2159 -0.36703) (xy -0.21844 -0.35687) (xy -0.22225 -0.34544) (xy -0.22352 -0.33528) (xy -0.22606 -0.32512)
						(xy -0.22733 -0.31369) (xy -0.22733 -0.30353) (xy -0.2286 -0.2921) (xy -0.22733 -0.28067) (xy -0.22733 -0.27051)
						(xy -0.22606 -0.25908) (xy -0.22352 -0.24892) (xy -0.22225 -0.23876) (xy -0.21844 -0.22733) (xy -0.2159 -0.21717)
						(xy -0.21209 -0.20701) (xy -0.20701 -0.19685) (xy -0.2032 -0.18796) (xy -0.19812 -0.1778) (xy -0.17272 -0.14224)
						(xy -0.1651 -0.13462) (xy -0.1651 0.7366) (xy -0.16256 0.76835) (xy -0.1524 0.8001) (xy -0.13716 0.82804)
						(xy -0.11684 0.85344) (xy -0.09144 0.87376) (xy -0.0635 0.889) (xy -0.03175 0.89916) (xy 0 0.9017)
						(xy 0.03175 0.89916) (xy 0.0635 0.889) (xy 0.09144 0.87376) (xy 0.11684 0.85344) (xy 0.13716 0.82804)
						(xy 0.1524 0.8001) (xy 0.16256 0.76835) (xy 0.1651 0.7366) (xy 0.1651 -0.13462) (xy 0.17272 -0.14224)
						(xy 0.19812 -0.1778) (xy 0.2032 -0.18796) (xy 0.20701 -0.19685) (xy 0.21209 -0.20701) (xy 0.2159 -0.21717)
						(xy 0.21844 -0.22733) (xy 0.22225 -0.23876) (xy 0.22352 -0.24892) (xy 0.22606 -0.25908) (xy 0.22733 -0.27051)
						(xy 0.22733 -0.28067) (xy 0.2286 -0.2921) (xy 0.22733 -0.30353) (xy 0.22733 -0.31369) (xy 0.22606 -0.32512)
						(xy 0.22352 -0.33528) (xy 0.22225 -0.34544) (xy 0.21844 -0.35687) (xy 0.2159 -0.36703) (xy 0.21209 -0.37719)
						(xy 0.20701 -0.38735) (xy 0.2032 -0.39624) (xy 0.19812 -0.4064) (xy 0.17272 -0.44196) (xy 0.1651 -0.44958)
						(xy 0.1651 -0.7366) (xy 0.16256 -0.76835) (xy 0.1524 -0.8001) (xy 0.13716 -0.82804) (xy 0.11684 -0.85344)
						(xy 0.09144 -0.87376) (xy 0.0635 -0.889) (xy 0.03175 -0.89916)
					)
					(width 0)
					(fill yes)
				)
			)
		)
		(pad "38" smd custom
			(at -20.550124 4.100068 180)
			(size 0.1143 0.1143)
			(layers "B.Cu" "B.Mask" "B.Paste")
			(net "GND")
			(options
				(clearance outline)
				(anchor circle)
			)
			(primitives
				(gr_poly
					(pts
						(xy 0 -0.9017) (xy -0.03175 -0.89916) (xy -0.0635 -0.889) (xy -0.09144 -0.87376) (xy -0.11684 -0.85344)
						(xy -0.13716 -0.82804) (xy -0.1524 -0.8001) (xy -0.16256 -0.76835) (xy -0.1651 -0.7366) (xy -0.1651 0.13462)
						(xy -0.17272 0.14224) (xy -0.19812 0.1778) (xy -0.2032 0.18796) (xy -0.20701 0.19685) (xy -0.21209 0.20701)
						(xy -0.2159 0.21717) (xy -0.21844 0.22733) (xy -0.22225 0.23876) (xy -0.22352 0.24892) (xy -0.22606 0.25908)
						(xy -0.22733 0.27051) (xy -0.22733 0.28067) (xy -0.2286 0.2921) (xy -0.22733 0.30353) (xy -0.22733 0.31369)
						(xy -0.22606 0.32512) (xy -0.22352 0.33528) (xy -0.22225 0.34544) (xy -0.21844 0.35687) (xy -0.2159 0.36703)
						(xy -0.21209 0.37719) (xy -0.20701 0.38735) (xy -0.2032 0.39624) (xy -0.19812 0.4064) (xy -0.17272 0.44196)
						(xy -0.1651 0.44958) (xy -0.1651 0.7366) (xy -0.16256 0.76835) (xy -0.1524 0.8001) (xy -0.13716 0.82804)
						(xy -0.11684 0.85344) (xy -0.09144 0.87376) (xy -0.0635 0.889) (xy -0.03175 0.89916) (xy 0 0.9017)
						(xy 0.03175 0.89916) (xy 0.0635 0.889) (xy 0.09144 0.87376) (xy 0.11684 0.85344) (xy 0.13716 0.82804)
						(xy 0.1524 0.8001) (xy 0.16256 0.76835) (xy 0.1651 0.7366) (xy 0.1651 0.44958) (xy 0.17272 0.44196)
						(xy 0.19812 0.4064) (xy 0.2032 0.39624) (xy 0.20701 0.38735) (xy 0.21209 0.37719) (xy 0.2159 0.36703)
						(xy 0.21844 0.35687) (xy 0.22225 0.34544) (xy 0.22352 0.33528) (xy 0.22606 0.32512) (xy 0.22733 0.31369)
						(xy 0.22733 0.30353) (xy 0.2286 0.2921) (xy 0.22733 0.28067) (xy 0.22733 0.27051) (xy 0.22606 0.25908)
						(xy 0.22352 0.24892) (xy 0.22225 0.23876) (xy 0.21844 0.22733) (xy 0.2159 0.21717) (xy 0.21209 0.20701)
						(xy 0.20701 0.19685) (xy 0.2032 0.18796) (xy 0.19812 0.1778) (xy 0.17272 0.14224) (xy 0.1651 0.13462)
						(xy 0.1651 -0.7366) (xy 0.16256 -0.76835) (xy 0.1524 -0.8001) (xy 0.13716 -0.82804) (xy 0.11684 -0.85344)
						(xy 0.09144 -0.87376) (xy 0.0635 -0.889) (xy 0.03175 -0.89916)
					)
					(width 0)
					(fill yes)
				)
			)
		)
		(pad "39" smd custom
			(at -20.249896 -4.100068 180)
			(size 0.1143 0.1143)
			(layers "B.Cu" "B.Mask" "B.Paste")
			(net "M_B_DQ17")
			(options
				(clearance outline)
				(anchor circle)
			)
			(primitives
				(gr_poly
					(pts
						(xy 0 -0.9017) (xy -0.03175 -0.89916) (xy -0.0635 -0.889) (xy -0.09144 -0.87376) (xy -0.11684 -0.85344)
						(xy -0.13716 -0.82804) (xy -0.1524 -0.8001) (xy -0.16256 -0.76835) (xy -0.1651 -0.7366) (xy -0.1651 -0.19685)
						(xy -0.17272 -0.18923) (xy -0.17907 -0.18034) (xy -0.18669 -0.17145) (xy -0.19177 -0.16256) (xy -0.19812 -0.15367)
						(xy -0.20828 -0.13335) (xy -0.21971 -0.10287) (xy -0.22225 -0.09271) (xy -0.22479 -0.08128) (xy -0.22606 -0.07112)
						(xy -0.2286 -0.05969) (xy -0.2286 -0.01651) (xy -0.22606 -0.00508) (xy -0.22479 0.00508) (xy -0.22225 0.01651)
						(xy -0.21971 0.02667) (xy -0.20828 0.05715) (xy -0.19812 0.07747) (xy -0.19177 0.08636) (xy -0.18669 0.09525)
						(xy -0.17907 0.10414) (xy -0.17272 0.11303) (xy -0.1651 0.12065) (xy -0.1651 0.7366) (xy -0.16256 0.76835)
						(xy -0.1524 0.8001) (xy -0.13716 0.82804) (xy -0.11684 0.85344) (xy -0.09144 0.87376) (xy -0.0635 0.889)
						(xy -0.03175 0.89916) (xy 0 0.9017) (xy 0.03175 0.89916) (xy 0.0635 0.889) (xy 0.09144 0.87376)
						(xy 0.11684 0.85344) (xy 0.13716 0.82804) (xy 0.1524 0.8001) (xy 0.16256 0.76835) (xy 0.1651 0.7366)
						(xy 0.1651 0.11938) (xy 0.17272 0.11176) (xy 0.19812 0.0762) (xy 0.2032 0.06604) (xy 0.20701 0.05715)
						(xy 0.21209 0.04699) (xy 0.2159 0.03683) (xy 0.21844 0.02667) (xy 0.22225 0.01524) (xy 0.22352 0.00508)
						(xy 0.22606 -0.00508) (xy 0.22733 -0.01651) (xy 0.22733 -0.02667) (xy 0.2286 -0.0381) (xy 0.22733 -0.04953)
						(xy 0.22733 -0.05969) (xy 0.22606 -0.07112) (xy 0.22352 -0.08128) (xy 0.22225 -0.09144) (xy 0.21844 -0.10287)
						(xy 0.2159 -0.11303) (xy 0.21209 -0.12319) (xy 0.20701 -0.13335) (xy 0.2032 -0.14224) (xy 0.19812 -0.1524)
						(xy 0.17272 -0.18796) (xy 0.1651 -0.19558) (xy 0.1651 -0.7366) (xy 0.16256 -0.76835) (xy 0.1524 -0.8001)
						(xy 0.13716 -0.82804) (xy 0.11684 -0.85344) (xy 0.09144 -0.87376) (xy 0.0635 -0.889) (xy 0.03175 -0.89916)
					)
					(width 0)
					(fill yes)
				)
			)
		)
		(pad "40" smd custom
			(at -19.949922 4.100068 180)
			(size 0.1143 0.1143)
			(layers "B.Cu" "B.Mask" "B.Paste")
			(net "M_B_DQ20")
			(options
				(clearance outline)
				(anchor circle)
			)
			(primitives
				(gr_poly
					(pts
						(xy 0 -0.9017) (xy -0.03175 -0.89916) (xy -0.0635 -0.889) (xy -0.09144 -0.87376) (xy -0.11684 -0.85344)
						(xy -0.13716 -0.82804) (xy -0.1524 -0.8001) (xy -0.16256 -0.76835) (xy -0.1651 -0.7366) (xy -0.1651 -0.11938)
						(xy -0.17272 -0.11176) (xy -0.19812 -0.0762) (xy -0.2032 -0.06604) (xy -0.20701 -0.05715) (xy -0.21209 -0.04699)
						(xy -0.2159 -0.03683) (xy -0.21844 -0.02667) (xy -0.22225 -0.01524) (xy -0.22352 -0.00508) (xy -0.22606 0.00508)
						(xy -0.22733 0.01651) (xy -0.22733 0.02667) (xy -0.2286 0.0381) (xy -0.22733 0.04953) (xy -0.22733 0.05969)
						(xy -0.22606 0.07112) (xy -0.22352 0.08128) (xy -0.22225 0.09144) (xy -0.21844 0.10287) (xy -0.2159 0.11303)
						(xy -0.21209 0.12319) (xy -0.20701 0.13335) (xy -0.2032 0.14224) (xy -0.19812 0.1524) (xy -0.17272 0.18796)
						(xy -0.1651 0.19558) (xy -0.1651 0.7366) (xy -0.16256 0.76835) (xy -0.1524 0.8001) (xy -0.13716 0.82804)
						(xy -0.11684 0.85344) (xy -0.09144 0.87376) (xy -0.0635 0.889) (xy -0.03175 0.89916) (xy 0 0.9017)
						(xy 0.03175 0.89916) (xy 0.0635 0.889) (xy 0.09144 0.87376) (xy 0.11684 0.85344) (xy 0.13716 0.82804)
						(xy 0.1524 0.8001) (xy 0.16256 0.76835) (xy 0.1651 0.7366) (xy 0.1651 0.19685) (xy 0.17272 0.18923)
						(xy 0.17907 0.18034) (xy 0.18669 0.17145) (xy 0.19177 0.16256) (xy 0.19812 0.15367) (xy 0.20828 0.13335)
						(xy 0.21971 0.10287) (xy 0.22225 0.09271) (xy 0.22479 0.08128) (xy 0.22606 0.07112) (xy 0.2286 0.05969)
						(xy 0.2286 0.01651) (xy 0.22606 0.00508) (xy 0.22479 -0.00508) (xy 0.22225 -0.01651) (xy 0.21971 -0.02667)
						(xy 0.20828 -0.05715) (xy 0.19812 -0.07747) (xy 0.19177 -0.08636) (xy 0.18669 -0.09525) (xy 0.17907 -0.10414)
						(xy 0.17272 -0.11303) (xy 0.1651 -0.12065) (xy 0.1651 -0.7366) (xy 0.16256 -0.76835) (xy 0.1524 -0.8001)
						(xy 0.13716 -0.82804) (xy 0.11684 -0.85344) (xy 0.09144 -0.87376) (xy 0.0635 -0.889) (xy 0.03175 -0.89916)
					)
					(width 0)
					(fill yes)
				)
			)
		)
		(pad "41" smd custom
			(at -19.649948 -4.100068 180)
			(size 0.1143 0.1143)
			(layers "B.Cu" "B.Mask" "B.Paste")
			(net "GND")
			(options
				(clearance outline)
				(anchor circle)
			)
			(primitives
				(gr_poly
					(pts
						(xy 0 -0.9017) (xy -0.03175 -0.89916) (xy -0.0635 -0.889) (xy -0.09144 -0.87376) (xy -0.11684 -0.85344)
						(xy -0.13716 -0.82804) (xy -0.1524 -0.8001) (xy -0.16256 -0.76835) (xy -0.1651 -0.7366) (xy -0.1651 -0.44958)
						(xy -0.17272 -0.44196) (xy -0.19812 -0.4064) (xy -0.2032 -0.39624) (xy -0.20701 -0.38735) (xy -0.21209 -0.37719)
						(xy -0.2159 -0.36703) (xy -0.21844 -0.35687) (xy -0.22225 -0.34544) (xy -0.22352 -0.33528) (xy -0.22606 -0.32512)
						(xy -0.22733 -0.31369) (xy -0.22733 -0.30353) (xy -0.2286 -0.2921) (xy -0.22733 -0.28067) (xy -0.22733 -0.27051)
						(xy -0.22606 -0.25908) (xy -0.22352 -0.24892) (xy -0.22225 -0.23876) (xy -0.21844 -0.22733) (xy -0.2159 -0.21717)
						(xy -0.21209 -0.20701) (xy -0.20701 -0.19685) (xy -0.2032 -0.18796) (xy -0.19812 -0.1778) (xy -0.17272 -0.14224)
						(xy -0.1651 -0.13462) (xy -0.1651 0.7366) (xy -0.16256 0.76835) (xy -0.1524 0.8001) (xy -0.13716 0.82804)
						(xy -0.11684 0.85344) (xy -0.09144 0.87376) (xy -0.0635 0.889) (xy -0.03175 0.89916) (xy 0 0.9017)
						(xy 0.03175 0.89916) (xy 0.0635 0.889) (xy 0.09144 0.87376) (xy 0.11684 0.85344) (xy 0.13716 0.82804)
						(xy 0.1524 0.8001) (xy 0.16256 0.76835) (xy 0.1651 0.7366) (xy 0.1651 -0.13462) (xy 0.17272 -0.14224)
						(xy 0.19812 -0.1778) (xy 0.2032 -0.18796) (xy 0.20701 -0.19685) (xy 0.21209 -0.20701) (xy 0.2159 -0.21717)
						(xy 0.21844 -0.22733) (xy 0.22225 -0.23876) (xy 0.22352 -0.24892) (xy 0.22606 -0.25908) (xy 0.22733 -0.27051)
						(xy 0.22733 -0.28067) (xy 0.2286 -0.2921) (xy 0.22733 -0.30353) (xy 0.22733 -0.31369) (xy 0.22606 -0.32512)
						(xy 0.22352 -0.33528) (xy 0.22225 -0.34544) (xy 0.21844 -0.35687) (xy 0.2159 -0.36703) (xy 0.21209 -0.37719)
						(xy 0.20701 -0.38735) (xy 0.2032 -0.39624) (xy 0.19812 -0.4064) (xy 0.17272 -0.44196) (xy 0.1651 -0.44958)
						(xy 0.1651 -0.7366) (xy 0.16256 -0.76835) (xy 0.1524 -0.8001) (xy 0.13716 -0.82804) (xy 0.11684 -0.85344)
						(xy 0.09144 -0.87376) (xy 0.0635 -0.889) (xy 0.03175 -0.89916)
					)
					(width 0)
					(fill yes)
				)
			)
		)
	)
)
